#ISCELL
  mstr_misc dns *
  *
#ISCELL
  pure_quanta quanta_title_block_c *
  *
#ISCELL
  standard offpage *
  page175_i1
#ISCELL
  pure_quanta_power vcc_core *
  page175_i10
#CELL
  pure_quanta q_cap *
  page175_i100
#ISCELL
  standard offpage *
  page175_i101
#ISCELL
  standard offpage *
  page175_i102
#ISCELL
  standard offpage *
  page175_i103
#ISCELL
  standard offpage *
  page175_i104
#ISCELL
  standard offpage *
  page175_i105
#ISCELL
  standard offpage *
  page175_i106
#ISCELL
  standard offpage *
  page175_i107
#ISCELL
  standard offpage *
  page175_i108
#ISCELL
  standard offpage *
  page175_i109
#ISCELL
  pure_quanta_power vcc_core *
  page175_i11
#ISCELL
  standard offpage *
  page175_i110
#ISCELL
  pure_quanta_power universal_gnd *
  page175_i111
#ISCELL
  pure_quanta_power universal_gnd *
  page175_i112
#ISCELL
  standard offpage *
  page175_i113
#ISCELL
  standard offpage *
  page175_i114
#ISCELL
  standard offpage *
  page175_i115
#ISCELL
  standard offpage *
  page175_i116
#ISCELL
  standard offpage *
  page175_i117
#ISCELL
  standard offpage *
  page175_i118
#ISCELL
  standard offpage *
  page175_i119
#CELL
  pure_quanta q_res *
  page175_i12
#ISCELL
  standard offpage *
  page175_i120
#ISCELL
  standard offpage *
  page175_i121
#ISCELL
  standard offpage *
  page175_i122
#ISCELL
  standard offpage *
  page175_i123
#ISCELL
  standard offpage *
  page175_i124
#ISCELL
  standard offpage *
  page175_i125
#CELL
  pure_quanta q_res *
  page175_i126
#ISCELL
  pure_quanta_power vcc_core *
  page175_i127
#CELL
  pure_quanta raa229620gnpha0 *
  page175_i128
#CELL
  pure_quanta q_res *
  page175_i129
#CELL
  pure_quanta mosfet_pch_gds_esd_protected *
  page175_i13
#CELL
  pure_quanta q_cap *
  page175_i130
#ISCELL
  pure_quanta_power universal_gnd *
  page175_i131
#ISCELL
  pure_quanta_power universal_gnd *
  page175_i132
#CELL
  pure_quanta q_cap *
  page175_i133
#ISCELL
  pure_quanta_power universal_gnd *
  page175_i134
#CELL
  pure_quanta q_cap *
  page175_i135
#CELL
  pure_quanta q_res *
  page175_i136
#CELL
  pure_quanta q_res *
  page175_i137
#ISCELL
  standard offpage *
  page175_i14
#ISCELL
  standard offpage *
  page175_i15
#ISCELL
  standard offpage *
  page175_i16
#CELL
  pure_quanta q_res *
  page175_i17
#ISCELL
  pure_quanta_power vcc_core *
  page175_i18
#CELL
  pure_quanta q_res *
  page175_i19
#CELL
  pure_quanta q_res *
  page175_i2
#ISCELL
  standard offpage *
  page175_i20
#ISCELL
  pure_quanta_power universal_gnd *
  page175_i21
#CELL
  pure_quanta q_res *
  page175_i22
#CELL
  pure_quanta q_res *
  page175_i23
#ISCELL
  pure_quanta_power vcc_core *
  page175_i24
#ISCELL
  pure_quanta_power universal_gnd *
  page175_i25
#ISCELL
  pure_quanta_power universal_gnd *
  page175_i26
#ISCELL
  standard offpage *
  page175_i27
#CELL
  pure_quanta q_res *
  page175_i28
#ISCELL
  standard offpage *
  page175_i29
#CELL
  pure_quanta q_cap *
  page175_i3
#ISCELL
  standard offpage *
  page175_i30
#ISCELL
  standard offpage *
  page175_i31
#CELL
  pure_quanta q_res *
  page175_i32
#CELL
  pure_quanta q_cap *
  page175_i33
#CELL
  pure_quanta q_cap *
  page175_i34
#CELL
  pure_quanta q_cap *
  page175_i35
#CELL
  pure_quanta q_res *
  page175_i36
#ISCELL
  standard offpage *
  page175_i37
#ISCELL
  standard offpage *
  page175_i38
#ISCELL
  standard offpage *
  page175_i39
#ISCELL
  pure_quanta_power universal_gnd *
  page175_i4
#CELL
  pure_quanta q_res *
  page175_i40
#ISCELL
  pure_quanta_power vcc_core *
  page175_i41
#CELL
  pure_quanta q_res *
  page175_i42
#CELL
  pure_quanta q_res *
  page175_i43
#CELL
  pure_quanta q_res *
  page175_i44
#ISCELL
  standard offpage *
  page175_i45
#ISCELL
  standard offpage *
  page175_i46
#ISCELL
  pure_quanta_power vcc_core *
  page175_i47
#ISCELL
  standard offpage *
  page175_i48
#ISCELL
  pure_quanta_power universal_gnd *
  page175_i49
#ISCELL
  standard offpage *
  page175_i5
#CELL
  pure_quanta q_cap *
  page175_i50
#CELL
  pure_quanta q_res *
  page175_i51
#ISCELL
  pure_quanta_power vcc_core *
  page175_i52
#CELL
  pure_quanta q_res *
  page175_i53
#CELL
  pure_quanta q_res *
  page175_i54
#CELL
  pure_quanta q_cap *
  page175_i55
#ISCELL
  pure_quanta_power vcc_core *
  page175_i56
#ISCELL
  pure_quanta_power universal_gnd *
  page175_i57
#ISCELL
  pure_quanta_power universal_gnd *
  page175_i58
#CELL
  pure_quanta q_res *
  page175_i59
#CELL
  pure_quanta mosfet_n *
  page175_i6
#CELL
  pure_quanta q_cap *
  page175_i60
#ISCELL
  pure_quanta_power universal_gnd *
  page175_i61
#ISCELL
  pure_quanta_power universal_gnd *
  page175_i62
#CELL
  pure_quanta q_cap *
  page175_i63
#ISCELL
  pure_quanta_power universal_gnd *
  page175_i64
#ISCELL
  pure_quanta_power vcc_core *
  page175_i65
#CELL
  pure_quanta q_res *
  page175_i66
#CELL
  pure_quanta q_res *
  page175_i67
#CELL
  pure_quanta q_res *
  page175_i68
#CELL
  pure_quanta q_cap *
  page175_i69
#ISCELL
  pure_quanta_power universal_gnd *
  page175_i7
#CELL
  pure_quanta q_res *
  page175_i70
#CELL
  pure_quanta q_res *
  page175_i71
#ISCELL
  pure_quanta_power universal_gnd *
  page175_i72
#CELL
  pure_quanta q_cap *
  page175_i73
#ISCELL
  pure_quanta_power universal_gnd *
  page175_i74
#CELL
  pure_quanta q_cap *
  page175_i75
#CELL
  pure_quanta q_res *
  page175_i76
#CELL
  pure_quanta q_res *
  page175_i77
#CELL
  pure_quanta q_res *
  page175_i78
#ISCELL
  pure_quanta_power vcc_core *
  page175_i79
#CELL
  pure_quanta q_res *
  page175_i8
#CELL
  pure_quanta q_cap *
  page175_i80
#CELL
  pure_quanta q_res *
  page175_i81
#CELL
  pure_quanta q_res *
  page175_i82
#CELL
  pure_quanta q_res *
  page175_i83
#CELL
  pure_quanta q_res *
  page175_i84
#CELL
  pure_quanta q_res *
  page175_i85
#CELL
  pure_quanta q_cap *
  page175_i86
#ISCELL
  pure_quanta_power universal_gnd *
  page175_i87
#CELL
  pure_quanta q_res *
  page175_i88
#CELL
  pure_quanta q_res *
  page175_i89
#CELL
  pure_quanta q_res *
  page175_i9
#CELL
  pure_quanta q_res *
  page175_i90
#CELL
  pure_quanta q_cap *
  page175_i91
#ISCELL
  pure_quanta_power universal_gnd *
  page175_i92
#ISCELL
  pure_quanta_power universal_gnd *
  page175_i93
#CELL
  pure_quanta q_cap *
  page175_i94
#ISCELL
  pure_quanta_power universal_gnd *
  page175_i95
#CELL
  pure_quanta q_cap *
  page175_i96
#ISCELL
  pure_quanta_power universal_gnd *
  page175_i97
#CELL
  pure_quanta q_cap *
  page175_i98
#ISCELL
  pure_quanta_power universal_gnd *
  page175_i99
